(kicad_pcb
	(version 20260206)
	(generator "pcbnew")
	(generator_version "10.0")
	(general
		(thickness 1.6)
		(legacy_teardrops no)
	)
	(paper "A4")
	(title_block
		(title "9052_F0T_PDB_Converter_Brick_F_V03_1208_1600_OCP.brd")
		(comment 1 "Grand Teton / footprints 433-438 of 578")
	)
	(layers
		(0 "F.Cu" signal "TOP")
		(4 "In1.Cu" signal "GND")
		(6 "In2.Cu" signal "IN1")
		(8 "In3.Cu" signal "GND1")
		(10 "In4.Cu" signal "VCC")
		(12 "In5.Cu" signal "VCC1")
		(14 "In6.Cu" signal "GND2")
		(16 "In7.Cu" signal "IN2")
		(18 "In8.Cu" signal "GND3")
		(2 "B.Cu" signal "BOTTOM")
		(9 "F.Adhes" user "F.Adhesive")
		(11 "B.Adhes" user "B.Adhesive")
		(13 "F.Paste" user "Package Geometry/Pastemask Top")
		(15 "B.Paste" user "Package Geometry/Pastemask Bottom")
		(5 "F.SilkS" user "Ref Des/Silkscreen Top")
		(7 "B.SilkS" user "Ref Des/Silkscreen Bottom")
		(1 "F.Mask" user "Board Geometry/Soldermask Top")
		(3 "B.Mask" user "Board Geometry/Soldermask Bottom")
		(17 "Dwgs.User" user "User.Drawings")
		(19 "Cmts.User" user "User.Comments")
		(21 "Eco1.User" user "User.Eco1")
		(23 "Eco2.User" user "User.Eco2")
		(25 "Edge.Cuts" user "Board Geometry/Outline")
		(27 "Margin" user)
		(31 "F.CrtYd" user "Package Geometry/Place Bound Top")
		(29 "B.CrtYd" user "Package Geometry/Place Bound Bottom")
		(35 "F.Fab" user "Ref Des/Assembly Top")
		(33 "B.Fab" user "Ref Des/Assembly Bottom")
	)
	(footprint ""
		(layer "B.Cu")
		(at 281.94 -39.243)
		(property "Reference" "U39"
			(at 3.3909 -2.11963 0)
			(unlocked yes)
			(layer "B.SilkS")
			(effects
				(font
					(size 0.7874 0.5842)
					(thickness 0.1524)
				)
				(justify left mirror)
			)
		)
		(property "Value" ""
			(at 0 0 0)
			(layer "B.Fab")
			(effects
				(font
					(size 1.27 1.27)
				)
				(justify mirror)
			)
		)
		(duplicate_pad_numbers_are_jumpers no)
		(fp_line
			(start -1.603248 -1.500124)
			(end -1.603248 1.500124)
			(stroke
				(width 0.1524)
				(type default)
			)
			(layer "B.SilkS")
		)
		(fp_line
			(start -1.603248 1.500124)
			(end 1.603248 1.500124)
			(stroke
				(width 0.1524)
				(type default)
			)
			(layer "B.SilkS")
		)
		(fp_line
			(start 1.603248 -1.500124)
			(end -1.603248 -1.500124)
			(stroke
				(width 0.1524)
				(type default)
			)
			(layer "B.SilkS")
		)
		(fp_line
			(start 1.603248 1.500124)
			(end 1.603248 -1.500124)
			(stroke
				(width 0.1524)
				(type default)
			)
			(layer "B.SilkS")
		)
		(fp_line
			(start -1.249934 -0.219964)
			(end -0.700024 -0.219964)
			(stroke
				(width 0.1)
				(type default)
			)
			(layer "B.Fab")
		)
		(fp_line
			(start -1.249934 0.219964)
			(end -1.249934 -0.219964)
			(stroke
				(width 0.1)
				(type default)
			)
			(layer "B.Fab")
		)
		(fp_line
			(start -0.700024 -1.500124)
			(end 0.700024 -1.500124)
			(stroke
				(width 0.1)
				(type default)
			)
			(layer "B.Fab")
		)
		(fp_line
			(start -0.700024 -0.219964)
			(end -0.700024 -1.500124)
			(stroke
				(width 0.1)
				(type default)
			)
			(layer "B.Fab")
		)
		(fp_line
			(start -0.700024 0.219964)
			(end -1.249934 0.219964)
			(stroke
				(width 0.1)
				(type default)
			)
			(layer "B.Fab")
		)
		(fp_line
			(start -0.700024 1.500124)
			(end -0.700024 0.219964)
			(stroke
				(width 0.1)
				(type default)
			)
			(layer "B.Fab")
		)
		(fp_line
			(start 0.6985 -0.729996)
			(end 0.6985 0.729996)
			(stroke
				(width 0.1)
				(type default)
			)
			(layer "B.Fab")
		)
		(fp_line
			(start 0.6985 0.729996)
			(end 1.249934 0.729996)
			(stroke
				(width 0.1)
				(type default)
			)
			(layer "B.Fab")
		)
		(fp_line
			(start 0.700024 -1.500124)
			(end 0.700024 -1.169924)
			(stroke
				(width 0.1)
				(type default)
			)
			(layer "B.Fab")
		)
		(fp_line
			(start 0.700024 -1.169924)
			(end 1.249934 -1.169924)
			(stroke
				(width 0.1)
				(type default)
			)
			(layer "B.Fab")
		)
		(fp_line
			(start 0.700024 1.169924)
			(end 0.700024 1.500124)
			(stroke
				(width 0.1)
				(type default)
			)
			(layer "B.Fab")
		)
		(fp_line
			(start 0.700024 1.500124)
			(end -0.700024 1.500124)
			(stroke
				(width 0.1)
				(type default)
			)
			(layer "B.Fab")
		)
		(fp_line
			(start 1.249934 -1.169924)
			(end 1.249934 -0.729996)
			(stroke
				(width 0.1)
				(type default)
			)
			(layer "B.Fab")
		)
		(fp_line
			(start 1.249934 -0.729996)
			(end 0.6985 -0.729996)
			(stroke
				(width 0.1)
				(type default)
			)
			(layer "B.Fab")
		)
		(fp_line
			(start 1.249934 0.729996)
			(end 1.249934 1.169924)
			(stroke
				(width 0.1)
				(type default)
			)
			(layer "B.Fab")
		)
		(fp_line
			(start 1.249934 1.169924)
			(end 0.700024 1.169924)
			(stroke
				(width 0.1)
				(type default)
			)
			(layer "B.Fab")
		)
		(fp_rect
			(start 0.700024 1.500124)
			(end -0.700024 -1.500124)
			(stroke
				(width 0)
				(type default)
			)
			(fill no)
			(layer "B.Fab")
		)
		(pad "D" smd rect
			(at -0.999998 0 270)
			(size 0.8128 0.9144)
			(layers "B.Cu" "B.Mask" "B.Paste")
			(net "P52V_HS1_EN_DELAY_N")
		)
		(pad "G" smd rect
			(at 0.999998 -0.94996 270)
			(size 0.8128 0.9144)
			(layers "B.Cu" "B.Mask" "B.Paste")
			(net "P52V_HS1_EN_DELAY")
		)
		(pad "S" smd rect
			(at 0.999998 0.94996 270)
			(size 0.8128 0.9144)
			(layers "B.Cu" "B.Mask" "B.Paste")
			(net "GND")
		)
	)
	(footprint ""
		(layer "B.Cu")
		(at 56.642 -76.327 180)
		(property "Reference" "R179"
			(at 0 0 0)
			(layer "B.SilkS")
			(hide yes)
			(effects
				(font
					(size 1.27 1.27)
				)
				(justify mirror)
			)
		)
		(property "Value" ""
			(at 0 0 0)
			(layer "B.Fab")
			(effects
				(font
					(size 1.27 1.27)
				)
				(justify mirror)
			)
		)
		(duplicate_pad_numbers_are_jumpers no)
		(fp_line
			(start 0.7874 0.4064)
			(end 0.7874 -0.4064)
			(stroke
				(width 0.1524)
				(type default)
			)
			(layer "B.SilkS")
		)
		(fp_line
			(start 0.7874 -0.4064)
			(end -0.7874 -0.4064)
			(stroke
				(width 0.1524)
				(type default)
			)
			(layer "B.SilkS")
		)
		(fp_line
			(start -0.7874 0.4064)
			(end 0.7874 0.4064)
			(stroke
				(width 0.1524)
				(type default)
			)
			(layer "B.SilkS")
		)
		(fp_line
			(start -0.7874 -0.4064)
			(end -0.7874 0.4064)
			(stroke
				(width 0.1524)
				(type default)
			)
			(layer "B.SilkS")
		)
		(fp_line
			(start 0.67945 0.3048)
			(end 0.67945 -0.305054)
			(stroke
				(width 0.1)
				(type default)
			)
			(layer "B.Fab")
		)
		(fp_line
			(start 0.67945 -0.305054)
			(end 0.12065 -0.305054)
			(stroke
				(width 0.1)
				(type default)
			)
			(layer "B.Fab")
		)
		(fp_line
			(start 0.12065 0.3048)
			(end 0.67945 0.3048)
			(stroke
				(width 0.1)
				(type default)
			)
			(layer "B.Fab")
		)
		(fp_line
			(start 0.12065 0.2794)
			(end 0.12065 0.3048)
			(stroke
				(width 0.1)
				(type default)
			)
			(layer "B.Fab")
		)
		(fp_line
			(start 0.12065 -0.2794)
			(end -0.12065 -0.2794)
			(stroke
				(width 0.1)
				(type default)
			)
			(layer "B.Fab")
		)
		(fp_line
			(start 0.12065 -0.305054)
			(end 0.12065 -0.2794)
			(stroke
				(width 0.1)
				(type default)
			)
			(layer "B.Fab")
		)
		(fp_line
			(start -0.120396 0.3048)
			(end -0.120396 0.2794)
			(stroke
				(width 0.1)
				(type default)
			)
			(layer "B.Fab")
		)
		(fp_line
			(start -0.120396 0.2794)
			(end 0.12065 0.2794)
			(stroke
				(width 0.1)
				(type default)
			)
			(layer "B.Fab")
		)
		(fp_line
			(start -0.12065 -0.2794)
			(end -0.12065 -0.3048)
			(stroke
				(width 0.1)
				(type default)
			)
			(layer "B.Fab")
		)
		(fp_line
			(start -0.12065 -0.3048)
			(end -0.67945 -0.3048)
			(stroke
				(width 0.1)
				(type default)
			)
			(layer "B.Fab")
		)
		(fp_line
			(start -0.67945 0.3048)
			(end -0.120396 0.3048)
			(stroke
				(width 0.1)
				(type default)
			)
			(layer "B.Fab")
		)
		(fp_line
			(start -0.67945 -0.3048)
			(end -0.67945 0.3048)
			(stroke
				(width 0.1)
				(type default)
			)
			(layer "B.Fab")
		)
		(pad "1" smd circle
			(at 0.40005 0)
			(size 0 0)
			(layers "B.Cu" "B.Mask" "B.Paste")
			(net "P12V_BRICK3_ALERT_N")
		)
		(pad "2" smd circle
			(at -0.40005 0)
			(size 0 0)
			(layers "B.Cu" "B.Mask" "B.Paste")
			(net "SMB_BRICK3_ALERT")
		)
	)
	(footprint ""
		(layer "B.Cu")
		(at 263.144 -35.433)
		(property "Reference" "PC4"
			(at 0 0 0)
			(layer "B.SilkS")
			(hide yes)
			(effects
				(font
					(size 1.27 1.27)
				)
				(justify mirror)
			)
		)
		(property "Value" ""
			(at 0 0 0)
			(layer "B.Fab")
			(effects
				(font
					(size 1.27 1.27)
				)
				(justify mirror)
			)
		)
		(duplicate_pad_numbers_are_jumpers no)
		(fp_line
			(start -0.7874 -0.4064)
			(end -0.7874 0.4064)
			(stroke
				(width 0.1524)
				(type default)
			)
			(layer "B.SilkS")
		)
		(fp_line
			(start -0.7874 0.4064)
			(end 0.7874 0.4064)
			(stroke
				(width 0.1524)
				(type default)
			)
			(layer "B.SilkS")
		)
		(fp_line
			(start 0.7874 -0.4064)
			(end -0.7874 -0.4064)
			(stroke
				(width 0.1524)
				(type default)
			)
			(layer "B.SilkS")
		)
		(fp_line
			(start 0.7874 0.4064)
			(end 0.7874 -0.4064)
			(stroke
				(width 0.1524)
				(type default)
			)
			(layer "B.SilkS")
		)
		(fp_line
			(start -0.67945 -0.3048)
			(end -0.67945 0.3048)
			(stroke
				(width 0.1)
				(type default)
			)
			(layer "B.Fab")
		)
		(fp_line
			(start -0.67945 0.3048)
			(end -0.120396 0.3048)
			(stroke
				(width 0.1)
				(type default)
			)
			(layer "B.Fab")
		)
		(fp_line
			(start -0.12065 -0.3048)
			(end -0.67945 -0.3048)
			(stroke
				(width 0.1)
				(type default)
			)
			(layer "B.Fab")
		)
		(fp_line
			(start -0.12065 -0.2794)
			(end -0.12065 -0.3048)
			(stroke
				(width 0.1)
				(type default)
			)
			(layer "B.Fab")
		)
		(fp_line
			(start -0.120396 0.2794)
			(end 0.12065 0.2794)
			(stroke
				(width 0.1)
				(type default)
			)
			(layer "B.Fab")
		)
		(fp_line
			(start -0.120396 0.3048)
			(end -0.120396 0.2794)
			(stroke
				(width 0.1)
				(type default)
			)
			(layer "B.Fab")
		)
		(fp_line
			(start 0.12065 -0.305054)
			(end 0.12065 -0.2794)
			(stroke
				(width 0.1)
				(type default)
			)
			(layer "B.Fab")
		)
		(fp_line
			(start 0.12065 -0.2794)
			(end -0.12065 -0.2794)
			(stroke
				(width 0.1)
				(type default)
			)
			(layer "B.Fab")
		)
		(fp_line
			(start 0.12065 0.2794)
			(end 0.12065 0.3048)
			(stroke
				(width 0.1)
				(type default)
			)
			(layer "B.Fab")
		)
		(fp_line
			(start 0.12065 0.3048)
			(end 0.67945 0.3048)
			(stroke
				(width 0.1)
				(type default)
			)
			(layer "B.Fab")
		)
		(fp_line
			(start 0.67945 -0.305054)
			(end 0.12065 -0.305054)
			(stroke
				(width 0.1)
				(type default)
			)
			(layer "B.Fab")
		)
		(fp_line
			(start 0.67945 0.3048)
			(end 0.67945 -0.305054)
			(stroke
				(width 0.1)
				(type default)
			)
			(layer "B.Fab")
		)
		(pad "1" smd circle
			(at 0.40005 0 180)
			(size 0 0)
			(layers "B.Cu" "B.Mask" "B.Paste")
			(net "P52V_HS1_INTVCC")
		)
		(pad "2" smd circle
			(at -0.40005 0 180)
			(size 0 0)
			(layers "B.Cu" "B.Mask" "B.Paste")
			(net "GND")
		)
	)
	(footprint ""
		(layer "B.Cu")
		(at 213.614 -67.183 90)
		(property "Reference" "R95"
			(at 0 0 90)
			(layer "B.SilkS")
			(hide yes)
			(effects
				(font
					(size 1.27 1.27)
				)
				(justify mirror)
			)
		)
		(property "Value" ""
			(at 0 0 90)
			(layer "B.Fab")
			(effects
				(font
					(size 1.27 1.27)
				)
				(justify mirror)
			)
		)
		(duplicate_pad_numbers_are_jumpers no)
		(fp_line
			(start 0.7874 -0.4064)
			(end -0.7874 -0.4064)
			(stroke
				(width 0.1524)
				(type default)
			)
			(layer "B.SilkS")
		)
		(fp_line
			(start -0.7874 -0.4064)
			(end -0.7874 0.4064)
			(stroke
				(width 0.1524)
				(type default)
			)
			(layer "B.SilkS")
		)
		(fp_line
			(start 0.7874 0.4064)
			(end 0.7874 -0.4064)
			(stroke
				(width 0.1524)
				(type default)
			)
			(layer "B.SilkS")
		)
		(fp_line
			(start -0.7874 0.4064)
			(end 0.7874 0.4064)
			(stroke
				(width 0.1524)
				(type default)
			)
			(layer "B.SilkS")
		)
		(fp_line
			(start 0.67945 -0.305054)
			(end 0.12065 -0.305054)
			(stroke
				(width 0.1)
				(type default)
			)
			(layer "B.Fab")
		)
		(fp_line
			(start 0.12065 -0.305054)
			(end 0.12065 -0.2794)
			(stroke
				(width 0.1)
				(type default)
			)
			(layer "B.Fab")
		)
		(fp_line
			(start -0.12065 -0.3048)
			(end -0.67945 -0.3048)
			(stroke
				(width 0.1)
				(type default)
			)
			(layer "B.Fab")
		)
		(fp_line
			(start -0.67945 -0.3048)
			(end -0.67945 0.3048)
			(stroke
				(width 0.1)
				(type default)
			)
			(layer "B.Fab")
		)
		(fp_line
			(start 0.12065 -0.2794)
			(end -0.12065 -0.2794)
			(stroke
				(width 0.1)
				(type default)
			)
			(layer "B.Fab")
		)
		(fp_line
			(start -0.12065 -0.2794)
			(end -0.12065 -0.3048)
			(stroke
				(width 0.1)
				(type default)
			)
			(layer "B.Fab")
		)
		(fp_line
			(start 0.12065 0.2794)
			(end 0.12065 0.3048)
			(stroke
				(width 0.1)
				(type default)
			)
			(layer "B.Fab")
		)
		(fp_line
			(start -0.120396 0.2794)
			(end 0.12065 0.2794)
			(stroke
				(width 0.1)
				(type default)
			)
			(layer "B.Fab")
		)
		(fp_line
			(start 0.67945 0.3048)
			(end 0.67945 -0.305054)
			(stroke
				(width 0.1)
				(type default)
			)
			(layer "B.Fab")
		)
		(fp_line
			(start 0.12065 0.3048)
			(end 0.67945 0.3048)
			(stroke
				(width 0.1)
				(type default)
			)
			(layer "B.Fab")
		)
		(fp_line
			(start -0.120396 0.3048)
			(end -0.120396 0.2794)
			(stroke
				(width 0.1)
				(type default)
			)
			(layer "B.Fab")
		)
		(fp_line
			(start -0.67945 0.3048)
			(end -0.120396 0.3048)
			(stroke
				(width 0.1)
				(type default)
			)
			(layer "B.Fab")
		)
		(pad "1" smd circle
			(at 0.40005 0 270)
			(size 0 0)
			(layers "B.Cu" "B.Mask" "B.Paste")
			(net "SKU_ID_0")
		)
		(pad "2" smd circle
			(at -0.40005 0 270)
			(size 0 0)
			(layers "B.Cu" "B.Mask" "B.Paste")
			(net "GND")
		)
	)
	(footprint ""
		(layer "B.Cu")
		(at 91.694 -76.708 90)
		(property "Reference" "R203"
			(at 0 0 90)
			(layer "B.SilkS")
			(hide yes)
			(effects
				(font
					(size 1.27 1.27)
				)
				(justify mirror)
			)
		)
		(property "Value" ""
			(at 0 0 90)
			(layer "B.Fab")
			(effects
				(font
					(size 1.27 1.27)
				)
				(justify mirror)
			)
		)
		(duplicate_pad_numbers_are_jumpers no)
		(fp_line
			(start 0.7874 -0.4064)
			(end -0.7874 -0.4064)
			(stroke
				(width 0.1524)
				(type default)
			)
			(layer "B.SilkS")
		)
		(fp_line
			(start -0.7874 -0.4064)
			(end -0.7874 0.4064)
			(stroke
				(width 0.1524)
				(type default)
			)
			(layer "B.SilkS")
		)
		(fp_line
			(start 0.7874 0.4064)
			(end 0.7874 -0.4064)
			(stroke
				(width 0.1524)
				(type default)
			)
			(layer "B.SilkS")
		)
		(fp_line
			(start -0.7874 0.4064)
			(end 0.7874 0.4064)
			(stroke
				(width 0.1524)
				(type default)
			)
			(layer "B.SilkS")
		)
		(fp_line
			(start 0.67945 -0.305054)
			(end 0.12065 -0.305054)
			(stroke
				(width 0.1)
				(type default)
			)
			(layer "B.Fab")
		)
		(fp_line
			(start 0.12065 -0.305054)
			(end 0.12065 -0.2794)
			(stroke
				(width 0.1)
				(type default)
			)
			(layer "B.Fab")
		)
		(fp_line
			(start -0.12065 -0.3048)
			(end -0.67945 -0.3048)
			(stroke
				(width 0.1)
				(type default)
			)
			(layer "B.Fab")
		)
		(fp_line
			(start -0.67945 -0.3048)
			(end -0.67945 0.3048)
			(stroke
				(width 0.1)
				(type default)
			)
			(layer "B.Fab")
		)
		(fp_line
			(start 0.12065 -0.2794)
			(end -0.12065 -0.2794)
			(stroke
				(width 0.1)
				(type default)
			)
			(layer "B.Fab")
		)
		(fp_line
			(start -0.12065 -0.2794)
			(end -0.12065 -0.3048)
			(stroke
				(width 0.1)
				(type default)
			)
			(layer "B.Fab")
		)
		(fp_line
			(start 0.12065 0.2794)
			(end 0.12065 0.3048)
			(stroke
				(width 0.1)
				(type default)
			)
			(layer "B.Fab")
		)
		(fp_line
			(start -0.120396 0.2794)
			(end 0.12065 0.2794)
			(stroke
				(width 0.1)
				(type default)
			)
			(layer "B.Fab")
		)
		(fp_line
			(start 0.67945 0.3048)
			(end 0.67945 -0.305054)
			(stroke
				(width 0.1)
				(type default)
			)
			(layer "B.Fab")
		)
		(fp_line
			(start 0.12065 0.3048)
			(end 0.67945 0.3048)
			(stroke
				(width 0.1)
				(type default)
			)
			(layer "B.Fab")
		)
		(fp_line
			(start -0.120396 0.3048)
			(end -0.120396 0.2794)
			(stroke
				(width 0.1)
				(type default)
			)
			(layer "B.Fab")
		)
		(fp_line
			(start -0.67945 0.3048)
			(end -0.120396 0.3048)
			(stroke
				(width 0.1)
				(type default)
			)
			(layer "B.Fab")
		)
		(pad "1" smd circle
			(at 0.40005 0 270)
			(size 0 0)
			(layers "B.Cu" "B.Mask" "B.Paste")
			(net "P3V3_AUX")
		)
		(pad "2" smd circle
			(at -0.40005 0 270)
			(size 0 0)
			(layers "B.Cu" "B.Mask" "B.Paste")
			(net "P12V_BRICK_PWRGD")
		)
	)
	(footprint ""
		(layer "B.Cu")
		(at 96.849946 -116.078 -90)
		(property "Reference" "R170"
			(at 0 0 90)
			(layer "B.SilkS")
			(hide yes)
			(effects
				(font
					(size 1.27 1.27)
				)
				(justify mirror)
			)
		)
		(property "Value" ""
			(at 0 0 90)
			(layer "B.Fab")
			(effects
				(font
					(size 1.27 1.27)
				)
				(justify mirror)
			)
		)
		(duplicate_pad_numbers_are_jumpers no)
		(fp_line
			(start -0.7874 0.4064)
			(end 0.7874 0.4064)
			(stroke
				(width 0.1524)
				(type default)
			)
			(layer "B.SilkS")
		)
		(fp_line
			(start 0.7874 0.4064)
			(end 0.7874 -0.4064)
			(stroke
				(width 0.1524)
				(type default)
			)
			(layer "B.SilkS")
		)
		(fp_line
			(start -0.7874 -0.4064)
			(end -0.7874 0.4064)
			(stroke
				(width 0.1524)
				(type default)
			)
			(layer "B.SilkS")
		)
		(fp_line
			(start 0.7874 -0.4064)
			(end -0.7874 -0.4064)
			(stroke
				(width 0.1524)
				(type default)
			)
			(layer "B.SilkS")
		)
		(fp_line
			(start -0.67945 0.3048)
			(end -0.120396 0.3048)
			(stroke
				(width 0.1)
				(type default)
			)
			(layer "B.Fab")
		)
		(fp_line
			(start -0.120396 0.3048)
			(end -0.120396 0.2794)
			(stroke
				(width 0.1)
				(type default)
			)
			(layer "B.Fab")
		)
		(fp_line
			(start 0.12065 0.3048)
			(end 0.67945 0.3048)
			(stroke
				(width 0.1)
				(type default)
			)
			(layer "B.Fab")
		)
		(fp_line
			(start 0.67945 0.3048)
			(end 0.67945 -0.305054)
			(stroke
				(width 0.1)
				(type default)
			)
			(layer "B.Fab")
		)
		(fp_line
			(start -0.120396 0.2794)
			(end 0.12065 0.2794)
			(stroke
				(width 0.1)
				(type default)
			)
			(layer "B.Fab")
		)
		(fp_line
			(start 0.12065 0.2794)
			(end 0.12065 0.3048)
			(stroke
				(width 0.1)
				(type default)
			)
			(layer "B.Fab")
		)
		(fp_line
			(start -0.12065 -0.2794)
			(end -0.12065 -0.3048)
			(stroke
				(width 0.1)
				(type default)
			)
			(layer "B.Fab")
		)
		(fp_line
			(start 0.12065 -0.2794)
			(end -0.12065 -0.2794)
			(stroke
				(width 0.1)
				(type default)
			)
			(layer "B.Fab")
		)
		(fp_line
			(start -0.67945 -0.3048)
			(end -0.67945 0.3048)
			(stroke
				(width 0.1)
				(type default)
			)
			(layer "B.Fab")
		)
		(fp_line
			(start -0.12065 -0.3048)
			(end -0.67945 -0.3048)
			(stroke
				(width 0.1)
				(type default)
			)
			(layer "B.Fab")
		)
		(fp_line
			(start 0.12065 -0.305054)
			(end 0.12065 -0.2794)
			(stroke
				(width 0.1)
				(type default)
			)
			(layer "B.Fab")
		)
		(fp_line
			(start 0.67945 -0.305054)
			(end 0.12065 -0.305054)
			(stroke
				(width 0.1)
				(type default)
			)
			(layer "B.Fab")
		)
		(pad "1" smd circle
			(at 0.40005 0 90)
			(size 0 0)
			(layers "B.Cu" "B.Mask" "B.Paste")
			(net "BRICK_P12V_1_EN_N")
		)
		(pad "2" smd circle
			(at -0.40005 0 90)
			(size 0 0)
			(layers "B.Cu" "B.Mask" "B.Paste")
			(net "BRICK_P12V1_ON_OFF_R")
		)
	)
)
